(kicad_pcb
	(version 20260206)
	(generator "pcbnew")
	(generator_version "10.0")
	(general
		(thickness 1.6)
		(legacy_teardrops no)
	)
	(paper "A4")
	(title_block
		(title "01162023_DA0F0TEBIF0_F0T_Expander_BD_F_brd_V02_OCP.brd")
		(comment 1 "Grand Teton / footprints 6164-6171 of 9728")
	)
	(layers
		(0 "F.Cu" signal "TOP")
		(4 "In1.Cu" signal "GND")
		(6 "In2.Cu" signal "VCC")
		(8 "In3.Cu" signal "VCC1")
		(10 "In4.Cu" signal "GND1")
		(12 "In5.Cu" signal "IN1")
		(14 "In6.Cu" signal "GND2")
		(16 "In7.Cu" signal "IN2")
		(18 "In8.Cu" signal "GND3")
		(20 "In9.Cu" signal "IN3")
		(22 "In10.Cu" signal "GND4")
		(24 "In11.Cu" signal "IN4")
		(26 "In12.Cu" signal "GND5")
		(28 "In13.Cu" signal "IN5")
		(30 "In14.Cu" signal "GND6")
		(32 "In15.Cu" signal "IN6")
		(34 "In16.Cu" signal "GND7")
		(2 "B.Cu" signal "BOTTOM")
		(9 "F.Adhes" user "F.Adhesive")
		(11 "B.Adhes" user "B.Adhesive")
		(13 "F.Paste" user "Package Geometry/Pastemask Top")
		(15 "B.Paste" user "Package Geometry/Pastemask Bottom")
		(5 "F.SilkS" user "Ref Des/Silkscreen Top")
		(7 "B.SilkS" user "Ref Des/Silkscreen Bottom")
		(1 "F.Mask" user "Board Geometry/Soldermask Top")
		(3 "B.Mask" user "Board Geometry/Soldermask Bottom")
		(17 "Dwgs.User" user "User.Drawings")
		(19 "Cmts.User" user "User.Comments")
		(21 "Eco1.User" user "User.Eco1")
		(23 "Eco2.User" user "User.Eco2")
		(25 "Edge.Cuts" user "Board Geometry/Outline")
		(27 "Margin" user)
		(31 "F.CrtYd" user "Package Geometry/Place Bound Top")
		(29 "B.CrtYd" user "Package Geometry/Place Bound Bottom")
		(35 "F.Fab" user "Ref Des/Assembly Top")
		(33 "B.Fab" user "Ref Des/Assembly Bottom")
	)
	(footprint ""
		(layer "F.Cu")
		(at 366.955578 -86.070694 180)
		(property "Reference" "R1624"
			(at 0 0 180)
			(layer "F.SilkS")
			(hide yes)
			(effects
				(font
					(size 1.27 1.27)
				)
			)
		)
		(property "Value" ""
			(at 0 0 180)
			(layer "F.Fab")
			(effects
				(font
					(size 1.27 1.27)
				)
			)
		)
		(duplicate_pad_numbers_are_jumpers no)
		(fp_line
			(start 0.7874 0.4064)
			(end -0.7874 0.4064)
			(stroke
				(width 0.1524)
				(type default)
			)
			(layer "F.SilkS")
		)
		(fp_line
			(start 0.7874 -0.4064)
			(end 0.7874 0.4064)
			(stroke
				(width 0.1524)
				(type default)
			)
			(layer "F.SilkS")
		)
		(fp_line
			(start -0.7874 0.4064)
			(end -0.7874 -0.4064)
			(stroke
				(width 0.1524)
				(type default)
			)
			(layer "F.SilkS")
		)
		(fp_line
			(start -0.7874 -0.4064)
			(end 0.7874 -0.4064)
			(stroke
				(width 0.1524)
				(type default)
			)
			(layer "F.SilkS")
		)
		(fp_line
			(start 0.67945 0.3048)
			(end 0.120396 0.3048)
			(stroke
				(width 0.1)
				(type default)
			)
			(layer "F.Fab")
		)
		(fp_line
			(start 0.67945 -0.3048)
			(end 0.67945 0.3048)
			(stroke
				(width 0.1)
				(type default)
			)
			(layer "F.Fab")
		)
		(fp_line
			(start 0.12065 -0.2794)
			(end 0.12065 -0.3048)
			(stroke
				(width 0.1)
				(type default)
			)
			(layer "F.Fab")
		)
		(fp_line
			(start 0.12065 -0.3048)
			(end 0.67945 -0.3048)
			(stroke
				(width 0.1)
				(type default)
			)
			(layer "F.Fab")
		)
		(fp_line
			(start 0.120396 0.3048)
			(end 0.120396 0.2794)
			(stroke
				(width 0.1)
				(type default)
			)
			(layer "F.Fab")
		)
		(fp_line
			(start 0.120396 0.2794)
			(end -0.12065 0.2794)
			(stroke
				(width 0.1)
				(type default)
			)
			(layer "F.Fab")
		)
		(fp_line
			(start -0.12065 0.3048)
			(end -0.67945 0.3048)
			(stroke
				(width 0.1)
				(type default)
			)
			(layer "F.Fab")
		)
		(fp_line
			(start -0.12065 0.2794)
			(end -0.12065 0.3048)
			(stroke
				(width 0.1)
				(type default)
			)
			(layer "F.Fab")
		)
		(fp_line
			(start -0.12065 -0.2794)
			(end 0.12065 -0.2794)
			(stroke
				(width 0.1)
				(type default)
			)
			(layer "F.Fab")
		)
		(fp_line
			(start -0.12065 -0.305054)
			(end -0.12065 -0.2794)
			(stroke
				(width 0.1)
				(type default)
			)
			(layer "F.Fab")
		)
		(fp_line
			(start -0.67945 0.3048)
			(end -0.67945 -0.305054)
			(stroke
				(width 0.1)
				(type default)
			)
			(layer "F.Fab")
		)
		(fp_line
			(start -0.67945 -0.305054)
			(end -0.12065 -0.305054)
			(stroke
				(width 0.1)
				(type default)
			)
			(layer "F.Fab")
		)
		(pad "1" smd circle
			(at -0.40005 0 180)
			(size 0 0)
			(layers "F.Cu" "F.Mask" "F.Paste")
			(net "SMB_BIC_I2C9_MUX1_SSD14_R_SDA")
		)
		(pad "2" smd circle
			(at 0.40005 0 180)
			(size 0 0)
			(layers "F.Cu" "F.Mask" "F.Paste")
			(net "SMB_BIC_I2C9_MUX1_SSD14_SDA")
		)
	)
	(footprint ""
		(layer "F.Cu")
		(at 20.514564 -66.32194 90)
		(property "Reference" "R5835"
			(at 0 0 90)
			(layer "F.SilkS")
			(hide yes)
			(effects
				(font
					(size 1.27 1.27)
				)
			)
		)
		(property "Value" ""
			(at 0 0 90)
			(layer "F.Fab")
			(effects
				(font
					(size 1.27 1.27)
				)
			)
		)
		(duplicate_pad_numbers_are_jumpers no)
		(fp_line
			(start 0.7874 -0.4064)
			(end 0.7874 0.4064)
			(stroke
				(width 0.1524)
				(type default)
			)
			(layer "F.SilkS")
		)
		(fp_line
			(start -0.7874 -0.4064)
			(end 0.7874 -0.4064)
			(stroke
				(width 0.1524)
				(type default)
			)
			(layer "F.SilkS")
		)
		(fp_line
			(start 0.7874 0.4064)
			(end -0.7874 0.4064)
			(stroke
				(width 0.1524)
				(type default)
			)
			(layer "F.SilkS")
		)
		(fp_line
			(start -0.7874 0.4064)
			(end -0.7874 -0.4064)
			(stroke
				(width 0.1524)
				(type default)
			)
			(layer "F.SilkS")
		)
		(fp_line
			(start -0.12065 -0.305054)
			(end -0.12065 -0.2794)
			(stroke
				(width 0.1)
				(type default)
			)
			(layer "F.Fab")
		)
		(fp_line
			(start -0.67945 -0.305054)
			(end -0.12065 -0.305054)
			(stroke
				(width 0.1)
				(type default)
			)
			(layer "F.Fab")
		)
		(fp_line
			(start 0.67945 -0.3048)
			(end 0.67945 0.3048)
			(stroke
				(width 0.1)
				(type default)
			)
			(layer "F.Fab")
		)
		(fp_line
			(start 0.12065 -0.3048)
			(end 0.67945 -0.3048)
			(stroke
				(width 0.1)
				(type default)
			)
			(layer "F.Fab")
		)
		(fp_line
			(start 0.12065 -0.2794)
			(end 0.12065 -0.3048)
			(stroke
				(width 0.1)
				(type default)
			)
			(layer "F.Fab")
		)
		(fp_line
			(start -0.12065 -0.2794)
			(end 0.12065 -0.2794)
			(stroke
				(width 0.1)
				(type default)
			)
			(layer "F.Fab")
		)
		(fp_line
			(start 0.120396 0.2794)
			(end -0.12065 0.2794)
			(stroke
				(width 0.1)
				(type default)
			)
			(layer "F.Fab")
		)
		(fp_line
			(start -0.12065 0.2794)
			(end -0.12065 0.3048)
			(stroke
				(width 0.1)
				(type default)
			)
			(layer "F.Fab")
		)
		(fp_line
			(start 0.67945 0.3048)
			(end 0.120396 0.3048)
			(stroke
				(width 0.1)
				(type default)
			)
			(layer "F.Fab")
		)
		(fp_line
			(start 0.120396 0.3048)
			(end 0.120396 0.2794)
			(stroke
				(width 0.1)
				(type default)
			)
			(layer "F.Fab")
		)
		(fp_line
			(start -0.12065 0.3048)
			(end -0.67945 0.3048)
			(stroke
				(width 0.1)
				(type default)
			)
			(layer "F.Fab")
		)
		(fp_line
			(start -0.67945 0.3048)
			(end -0.67945 -0.305054)
			(stroke
				(width 0.1)
				(type default)
			)
			(layer "F.Fab")
		)
		(pad "1" smd circle
			(at -0.40005 0 90)
			(size 0 0)
			(layers "F.Cu" "F.Mask" "F.Paste")
			(net "SSD0_PWR_EN_R")
		)
		(pad "2" smd circle
			(at 0.40005 0 90)
			(size 0 0)
			(layers "F.Cu" "F.Mask" "F.Paste")
			(net "P12V_SSD0_CO_EN")
		)
	)
	(footprint ""
		(layer "F.Cu")
		(at 125.186948 -350.098614 90)
		(property "Reference" "C369"
			(at 0 0 90)
			(layer "F.SilkS")
			(hide yes)
			(effects
				(font
					(size 1.27 1.27)
				)
			)
		)
		(property "Value" ""
			(at 0 0 90)
			(layer "F.Fab")
			(effects
				(font
					(size 1.27 1.27)
				)
			)
		)
		(duplicate_pad_numbers_are_jumpers no)
		(fp_line
			(start 0.299974 -0.150114)
			(end 0.299974 0.150114)
			(stroke
				(width 0.1)
				(type default)
			)
			(layer "F.Fab")
		)
		(fp_line
			(start -0.299974 -0.150114)
			(end 0.299974 -0.150114)
			(stroke
				(width 0.1)
				(type default)
			)
			(layer "F.Fab")
		)
		(fp_line
			(start 0.299974 0.150114)
			(end -0.299974 0.150114)
			(stroke
				(width 0.1)
				(type default)
			)
			(layer "F.Fab")
		)
		(fp_line
			(start -0.299974 0.150114)
			(end -0.299974 -0.150114)
			(stroke
				(width 0.1)
				(type default)
			)
			(layer "F.Fab")
		)
		(pad "1" smd rect
			(at -0.2667 0 90)
			(size 0.3048 0.381)
			(layers "F.Cu" "F.Mask" "F.Paste")
			(net "P5E_PEX1_STN6_TX_DN<97>")
		)
		(pad "2" smd rect
			(at 0.2667 0 90)
			(size 0.3048 0.381)
			(layers "F.Cu" "F.Mask" "F.Paste")
			(net "P5E_PEX1_STN6_TX_C_DN<97>")
		)
	)
	(footprint ""
		(layer "F.Cu")
		(at 38.608 -159.4104 180)
		(property "Reference" "R2"
			(at 0 0 180)
			(layer "F.SilkS")
			(hide yes)
			(effects
				(font
					(size 1.27 1.27)
				)
			)
		)
		(property "Value" ""
			(at 0 0 180)
			(layer "F.Fab")
			(effects
				(font
					(size 1.27 1.27)
				)
			)
		)
		(duplicate_pad_numbers_are_jumpers no)
		(fp_line
			(start 0.7874 0.4064)
			(end -0.7874 0.4064)
			(stroke
				(width 0.1524)
				(type default)
			)
			(layer "F.SilkS")
		)
		(fp_line
			(start 0.7874 -0.4064)
			(end 0.7874 0.4064)
			(stroke
				(width 0.1524)
				(type default)
			)
			(layer "F.SilkS")
		)
		(fp_line
			(start -0.7874 0.4064)
			(end -0.7874 -0.4064)
			(stroke
				(width 0.1524)
				(type default)
			)
			(layer "F.SilkS")
		)
		(fp_line
			(start -0.7874 -0.4064)
			(end 0.7874 -0.4064)
			(stroke
				(width 0.1524)
				(type default)
			)
			(layer "F.SilkS")
		)
		(fp_line
			(start 0.67945 0.3048)
			(end 0.120396 0.3048)
			(stroke
				(width 0.1)
				(type default)
			)
			(layer "F.Fab")
		)
		(fp_line
			(start 0.67945 -0.3048)
			(end 0.67945 0.3048)
			(stroke
				(width 0.1)
				(type default)
			)
			(layer "F.Fab")
		)
		(fp_line
			(start 0.12065 -0.2794)
			(end 0.12065 -0.3048)
			(stroke
				(width 0.1)
				(type default)
			)
			(layer "F.Fab")
		)
		(fp_line
			(start 0.12065 -0.3048)
			(end 0.67945 -0.3048)
			(stroke
				(width 0.1)
				(type default)
			)
			(layer "F.Fab")
		)
		(fp_line
			(start 0.120396 0.3048)
			(end 0.120396 0.2794)
			(stroke
				(width 0.1)
				(type default)
			)
			(layer "F.Fab")
		)
		(fp_line
			(start 0.120396 0.2794)
			(end -0.12065 0.2794)
			(stroke
				(width 0.1)
				(type default)
			)
			(layer "F.Fab")
		)
		(fp_line
			(start -0.12065 0.3048)
			(end -0.67945 0.3048)
			(stroke
				(width 0.1)
				(type default)
			)
			(layer "F.Fab")
		)
		(fp_line
			(start -0.12065 0.2794)
			(end -0.12065 0.3048)
			(stroke
				(width 0.1)
				(type default)
			)
			(layer "F.Fab")
		)
		(fp_line
			(start -0.12065 -0.2794)
			(end 0.12065 -0.2794)
			(stroke
				(width 0.1)
				(type default)
			)
			(layer "F.Fab")
		)
		(fp_line
			(start -0.12065 -0.305054)
			(end -0.12065 -0.2794)
			(stroke
				(width 0.1)
				(type default)
			)
			(layer "F.Fab")
		)
		(fp_line
			(start -0.67945 0.3048)
			(end -0.67945 -0.305054)
			(stroke
				(width 0.1)
				(type default)
			)
			(layer "F.Fab")
		)
		(fp_line
			(start -0.67945 -0.305054)
			(end -0.12065 -0.305054)
			(stroke
				(width 0.1)
				(type default)
			)
			(layer "F.Fab")
		)
		(pad "1" smd circle
			(at -0.40005 0 180)
			(size 0 0)
			(layers "F.Cu" "F.Mask" "F.Paste")
			(net "NIC0_MAIN_PWR_EN_R")
		)
		(pad "2" smd circle
			(at 0.40005 0 180)
			(size 0 0)
			(layers "F.Cu" "F.Mask" "F.Paste")
			(net "NIC0_MAIN_PWR_EN")
		)
	)
	(footprint ""
		(layer "F.Cu")
		(at 209.825844 -124.260864)
		(property "Reference" "PC485"
			(at 0 0 0)
			(layer "F.SilkS")
			(hide yes)
			(effects
				(font
					(size 1.27 1.27)
				)
			)
		)
		(property "Value" ""
			(at 0 0 0)
			(layer "F.Fab")
			(effects
				(font
					(size 1.27 1.27)
				)
			)
		)
		(duplicate_pad_numbers_are_jumpers no)
		(fp_line
			(start -1.524 -0.762)
			(end 1.524 -0.762)
			(stroke
				(width 0.1524)
				(type default)
			)
			(layer "F.SilkS")
		)
		(fp_line
			(start -1.524 0.762)
			(end -1.524 -0.762)
			(stroke
				(width 0.1524)
				(type default)
			)
			(layer "F.SilkS")
		)
		(fp_line
			(start 1.524 -0.762)
			(end 1.524 0.762)
			(stroke
				(width 0.1524)
				(type default)
			)
			(layer "F.SilkS")
		)
		(fp_line
			(start 1.524 0.762)
			(end -1.524 0.762)
			(stroke
				(width 0.1524)
				(type default)
			)
			(layer "F.SilkS")
		)
		(fp_line
			(start -1.1049 -0.724916)
			(end -1.1049 0.724916)
			(stroke
				(width 0.1)
				(type default)
			)
			(layer "F.Fab")
		)
		(fp_line
			(start -1.1049 0.724916)
			(end 1.1049 0.724916)
			(stroke
				(width 0.1)
				(type default)
			)
			(layer "F.Fab")
		)
		(fp_line
			(start 1.1049 -0.724916)
			(end -1.1049 -0.724916)
			(stroke
				(width 0.1)
				(type default)
			)
			(layer "F.Fab")
		)
		(fp_line
			(start 1.1049 0.724916)
			(end 1.1049 -0.724916)
			(stroke
				(width 0.1)
				(type default)
			)
			(layer "F.Fab")
		)
		(pad "1" smd rect
			(at -0.889 0 180)
			(size 1.016 1.27)
			(layers "F.Cu" "F.Mask" "F.Paste")
			(net "GND")
		)
		(pad "2" smd rect
			(at 0.889 0 180)
			(size 1.016 1.27)
			(layers "F.Cu" "F.Mask" "F.Paste")
			(net "P3V3_AUX")
		)
	)
	(footprint ""
		(layer "F.Cu")
		(at 142.678658 -308.611524 45)
		(property "Reference" "R4361"
			(at 0 0 45)
			(layer "F.SilkS")
			(hide yes)
			(effects
				(font
					(size 1.27 1.27)
				)
			)
		)
		(property "Value" ""
			(at 0 0 45)
			(layer "F.Fab")
			(effects
				(font
					(size 1.27 1.27)
				)
			)
		)
		(duplicate_pad_numbers_are_jumpers no)
		(fp_line
			(start -0.787389 -0.406267)
			(end 0.787389 -0.406267)
			(stroke
				(width 0.1524)
				(type default)
			)
			(layer "F.SilkS")
		)
		(fp_line
			(start -0.787389 0.406267)
			(end -0.787389 -0.406267)
			(stroke
				(width 0.1524)
				(type default)
			)
			(layer "F.SilkS")
		)
		(fp_line
			(start 0.787389 -0.406267)
			(end 0.787389 0.406267)
			(stroke
				(width 0.1524)
				(type default)
			)
			(layer "F.SilkS")
		)
		(fp_line
			(start 0.787389 0.406267)
			(end -0.787389 0.406267)
			(stroke
				(width 0.1524)
				(type default)
			)
			(layer "F.SilkS")
		)
		(fp_line
			(start -0.679446 -0.305149)
			(end -0.120695 -0.304969)
			(stroke
				(width 0.1)
				(type default)
			)
			(layer "F.Fab")
		)
		(fp_line
			(start -0.120695 -0.304969)
			(end -0.120695 -0.279466)
			(stroke
				(width 0.1)
				(type default)
			)
			(layer "F.Fab")
		)
		(fp_line
			(start -0.120695 -0.279466)
			(end 0.120695 -0.279466)
			(stroke
				(width 0.1)
				(type default)
			)
			(layer "F.Fab")
		)
		(fp_line
			(start -0.679446 0.30479)
			(end -0.679446 -0.305149)
			(stroke
				(width 0.1)
				(type default)
			)
			(layer "F.Fab")
		)
		(fp_line
			(start 0.120515 -0.30479)
			(end 0.679446 -0.30479)
			(stroke
				(width 0.1)
				(type default)
			)
			(layer "F.Fab")
		)
		(fp_line
			(start 0.120695 -0.279466)
			(end 0.120515 -0.30479)
			(stroke
				(width 0.1)
				(type default)
			)
			(layer "F.Fab")
		)
		(fp_line
			(start -0.120695 0.279466)
			(end -0.120515 0.30479)
			(stroke
				(width 0.1)
				(type default)
			)
			(layer "F.Fab")
		)
		(fp_line
			(start -0.120515 0.30479)
			(end -0.679446 0.30479)
			(stroke
				(width 0.1)
				(type default)
			)
			(layer "F.Fab")
		)
		(fp_line
			(start 0.679446 -0.30479)
			(end 0.679446 0.30479)
			(stroke
				(width 0.1)
				(type default)
			)
			(layer "F.Fab")
		)
		(fp_line
			(start 0.120335 0.279466)
			(end -0.120695 0.279466)
			(stroke
				(width 0.1)
				(type default)
			)
			(layer "F.Fab")
		)
		(fp_line
			(start 0.120515 0.30479)
			(end 0.120335 0.279466)
			(stroke
				(width 0.1)
				(type default)
			)
			(layer "F.Fab")
		)
		(fp_line
			(start 0.679446 0.30479)
			(end 0.120515 0.30479)
			(stroke
				(width 0.1)
				(type default)
			)
			(layer "F.Fab")
		)
		(pad "1" smd circle
			(at -0.40005 0 45)
			(size 0 0)
			(layers "F.Cu" "F.Mask" "F.Paste")
			(net "P1V8_PEX")
		)
		(pad "2" smd circle
			(at 0.40005 0 45)
			(size 0 0)
			(layers "F.Cu" "F.Mask" "F.Paste")
			(net "IRQ_PEX1_CLKREQ_INT_N")
		)
	)
	(footprint ""
		(layer "F.Cu")
		(at 155.380436 -99.288854)
		(property "Reference" "C274"
			(at 0 0 0)
			(layer "F.SilkS")
			(hide yes)
			(effects
				(font
					(size 1.27 1.27)
				)
			)
		)
		(property "Value" ""
			(at 0 0 0)
			(layer "F.Fab")
			(effects
				(font
					(size 1.27 1.27)
				)
			)
		)
		(duplicate_pad_numbers_are_jumpers no)
		(fp_line
			(start -0.299974 -0.150114)
			(end 0.299974 -0.150114)
			(stroke
				(width 0.1)
				(type default)
			)
			(layer "F.Fab")
		)
		(fp_line
			(start -0.299974 0.150114)
			(end -0.299974 -0.150114)
			(stroke
				(width 0.1)
				(type default)
			)
			(layer "F.Fab")
		)
		(fp_line
			(start 0.299974 -0.150114)
			(end 0.299974 0.150114)
			(stroke
				(width 0.1)
				(type default)
			)
			(layer "F.Fab")
		)
		(fp_line
			(start 0.299974 0.150114)
			(end -0.299974 0.150114)
			(stroke
				(width 0.1)
				(type default)
			)
			(layer "F.Fab")
		)
		(pad "1" smd rect
			(at -0.2667 0)
			(size 0.3048 0.381)
			(layers "F.Cu" "F.Mask" "F.Paste")
			(net "P5E_PEX1_STN1_TX_DP<16>")
		)
		(pad "2" smd rect
			(at 0.2667 0)
			(size 0.3048 0.381)
			(layers "F.Cu" "F.Mask" "F.Paste")
			(net "P5E_PEX1_STN1_TX_C_DP<16>")
		)
	)
	(footprint ""
		(layer "F.Cu")
		(at 385.548124 -102.009702)
		(property "Reference" "C695"
			(at 0 0 0)
			(layer "F.SilkS")
			(hide yes)
			(effects
				(font
					(size 1.27 1.27)
				)
			)
		)
		(property "Value" ""
			(at 0 0 0)
			(layer "F.Fab")
			(effects
				(font
					(size 1.27 1.27)
				)
			)
		)
		(duplicate_pad_numbers_are_jumpers no)
		(fp_line
			(start -0.299974 -0.150114)
			(end 0.299974 -0.150114)
			(stroke
				(width 0.1)
				(type default)
			)
			(layer "F.Fab")
		)
		(fp_line
			(start -0.299974 0.150114)
			(end -0.299974 -0.150114)
			(stroke
				(width 0.1)
				(type default)
			)
			(layer "F.Fab")
		)
		(fp_line
			(start 0.299974 -0.150114)
			(end 0.299974 0.150114)
			(stroke
				(width 0.1)
				(type default)
			)
			(layer "F.Fab")
		)
		(fp_line
			(start 0.299974 0.150114)
			(end -0.299974 0.150114)
			(stroke
				(width 0.1)
				(type default)
			)
			(layer "F.Fab")
		)
		(pad "1" smd rect
			(at -0.2667 0)
			(size 0.3048 0.381)
			(layers "F.Cu" "F.Mask" "F.Paste")
			(net "P5E_PEX3_STN1_TX_DP<17>")
		)
		(pad "2" smd rect
			(at 0.2667 0)
			(size 0.3048 0.381)
			(layers "F.Cu" "F.Mask" "F.Paste")
			(net "P5E_PEX3_STN1_TX_C_DP<17>")
		)
	)
)
